(kicad_pcb
	(version 20260206)
	(generator "pcbnew")
	(generator_version "10.0")
	(general
		(thickness 1.6)
		(legacy_teardrops no)
	)
	(paper "A4")
	(title_block
		(title "v1-chassis-manager — T6M_CM_d_v01_1031_1645.brd")
		(comment 1 "Open CloudServer (Microsoft) / footprints 1470-1479 of 2512")
	)
	(layers
		(0 "F.Cu" signal "TOP")
		(4 "In1.Cu" signal "GND1")
		(6 "In2.Cu" signal "IN1")
		(8 "In3.Cu" signal "VCC1")
		(10 "In4.Cu" signal "VCC2")
		(12 "In5.Cu" signal "GND2")
		(14 "In6.Cu" signal "IN2")
		(16 "In7.Cu" signal "IN3")
		(18 "In8.Cu" signal "GND3")
		(2 "B.Cu" signal "BOTTOM")
		(9 "F.Adhes" user "F.Adhesive")
		(11 "B.Adhes" user "B.Adhesive")
		(13 "F.Paste" user "Package Geometry/Pastemask Top")
		(15 "B.Paste" user "Package Geometry/Pastemask Bottom")
		(5 "F.SilkS" user "Ref Des/Silkscreen Top")
		(7 "B.SilkS" user "Ref Des/Silkscreen Bottom")
		(1 "F.Mask" user "Board Geometry/Soldermask Top")
		(3 "B.Mask" user "Board Geometry/Soldermask Bottom")
		(17 "Dwgs.User" user "User.Drawings")
		(19 "Cmts.User" user "User.Comments")
		(21 "Eco1.User" user "User.Eco1")
		(23 "Eco2.User" user "User.Eco2")
		(25 "Edge.Cuts" user "Board Geometry/Outline")
		(27 "Margin" user)
		(31 "F.CrtYd" user "Package Geometry/Place Bound Top")
		(29 "B.CrtYd" user "Package Geometry/Place Bound Bottom")
		(35 "F.Fab" user "Ref Des/Assembly Top")
		(33 "B.Fab" user "Ref Des/Assembly Bottom")
	)
	(footprint ""
		(layer "F.Cu")
		(at 15.499588 -46.300898 90)
		(property "Reference" "C505"
			(at -8.563864 -0.833628 90)
			(unlocked yes)
			(layer "F.SilkS")
			(effects
				(font
					(size 0.7874 0.5842)
					(thickness 0.1524)
				)
				(justify left)
			)
		)
		(property "Value" ""
			(at 0 0 90)
			(layer "F.Fab")
			(effects
				(font
					(size 1.27 1.27)
				)
			)
		)
		(duplicate_pad_numbers_are_jumpers no)
		(fp_line
			(start 0.7874 -0.4064)
			(end 0.7874 0.4064)
			(stroke
				(width 0.1524)
				(type default)
			)
			(layer "F.SilkS")
		)
		(fp_line
			(start -0.7874 -0.4064)
			(end 0.7874 -0.4064)
			(stroke
				(width 0.1524)
				(type default)
			)
			(layer "F.SilkS")
		)
		(fp_line
			(start 0 0.381)
			(end 0 -0.381)
			(stroke
				(width 0.1524)
				(type default)
			)
			(layer "F.SilkS")
		)
		(fp_line
			(start 0.7874 0.4064)
			(end -0.7874 0.4064)
			(stroke
				(width 0.1524)
				(type default)
			)
			(layer "F.SilkS")
		)
		(fp_line
			(start -0.7874 0.4064)
			(end -0.7874 -0.4064)
			(stroke
				(width 0.1524)
				(type default)
			)
			(layer "F.SilkS")
		)
		(fp_poly
			(pts
				(xy -0.5334 0.254) (xy -0.635 0.254) (xy -0.635 0.2286) (xy -0.635 -0.254) (xy -0.5334 -0.254) (xy -0.5334 -0.2794)
				(xy 0.5334 -0.2794) (xy 0.5334 -0.254) (xy 0.635 -0.254) (xy 0.635 0.254) (xy 0.5334 0.254) (xy 0.5334 0.2794)
				(xy -0.508 0.2794) (xy -0.5334 0.2794)
			)
			(stroke
				(width 0)
				(type default)
			)
			(fill no)
			(layer "F.CrtYd")
		)
		(pad "1" smd rect
			(at 0.40005 0 90)
			(size 0.4572 0.508)
			(layers "F.Cu" "F.Mask" "F.Paste")
			(net "CRT_DDCDATA")
		)
		(pad "2" smd rect
			(at -0.40005 0 90)
			(size 0.4572 0.508)
			(layers "F.Cu" "F.Mask" "F.Paste")
			(net "GND")
		)
	)
	(footprint ""
		(layer "F.Cu")
		(at 55.049166 -96.709992 90)
		(property "Reference" "R80"
			(at -54.98719 28.429712 90)
			(unlocked yes)
			(layer "F.SilkS")
			(effects
				(font
					(size 0.7874 0.5842)
					(thickness 0.1524)
				)
				(justify left)
			)
		)
		(property "Value" ""
			(at 0 0 90)
			(layer "F.Fab")
			(effects
				(font
					(size 1.27 1.27)
				)
			)
		)
		(duplicate_pad_numbers_are_jumpers no)
		(fp_line
			(start 0.7874 -0.4064)
			(end 0.7874 0.4064)
			(stroke
				(width 0.1524)
				(type default)
			)
			(layer "F.SilkS")
		)
		(fp_line
			(start -0.7874 -0.4064)
			(end 0.7874 -0.4064)
			(stroke
				(width 0.1524)
				(type default)
			)
			(layer "F.SilkS")
		)
		(fp_line
			(start 0.7874 0.4064)
			(end -0.7874 0.4064)
			(stroke
				(width 0.1524)
				(type default)
			)
			(layer "F.SilkS")
		)
		(fp_line
			(start -0.7874 0.4064)
			(end -0.7874 -0.4064)
			(stroke
				(width 0.1524)
				(type default)
			)
			(layer "F.SilkS")
		)
		(fp_poly
			(pts
				(xy -0.508 0.2794) (xy -0.508 0.2286) (xy -0.635 0.2286) (xy -0.635 -0.254) (xy -0.5334 -0.254)
				(xy -0.5334 -0.2794) (xy 0.5334 -0.2794) (xy 0.5334 -0.254) (xy 0.635 -0.254) (xy 0.635 0.254) (xy 0.5334 0.254)
				(xy 0.5334 0.2794)
			)
			(stroke
				(width 0)
				(type default)
			)
			(fill no)
			(layer "F.CrtYd")
		)
		(pad "1" smd rect
			(at 0.40005 0 90)
			(size 0.4572 0.508)
			(layers "F.Cu" "F.Mask" "F.Paste")
			(net "GND")
		)
		(pad "2" smd rect
			(at -0.40005 0 90)
			(size 0.4572 0.508)
			(layers "F.Cu" "F.Mask" "F.Paste")
			(net "PD_CPU_NODE1_DFX_GPIO_GRP0_6")
		)
	)
	(footprint ""
		(layer "F.Cu")
		(at 138.880088 -69.662548 180)
		(property "Reference" "R501"
			(at 3.772916 0.378968 0)
			(unlocked yes)
			(layer "F.SilkS")
			(effects
				(font
					(size 0.7874 0.5842)
					(thickness 0.1524)
				)
				(justify left)
			)
		)
		(property "Value" ""
			(at 0 0 180)
			(layer "F.Fab")
			(effects
				(font
					(size 1.27 1.27)
				)
			)
		)
		(duplicate_pad_numbers_are_jumpers no)
		(fp_line
			(start 0.7874 0.4064)
			(end -0.7874 0.4064)
			(stroke
				(width 0.1524)
				(type default)
			)
			(layer "F.SilkS")
		)
		(fp_line
			(start 0.7874 -0.4064)
			(end 0.7874 0.4064)
			(stroke
				(width 0.1524)
				(type default)
			)
			(layer "F.SilkS")
		)
		(fp_line
			(start -0.7874 0.4064)
			(end -0.7874 -0.4064)
			(stroke
				(width 0.1524)
				(type default)
			)
			(layer "F.SilkS")
		)
		(fp_line
			(start -0.7874 -0.4064)
			(end 0.7874 -0.4064)
			(stroke
				(width 0.1524)
				(type default)
			)
			(layer "F.SilkS")
		)
		(fp_poly
			(pts
				(xy -0.508 0.2794) (xy -0.508 0.2286) (xy -0.635 0.2286) (xy -0.635 -0.254) (xy -0.5334 -0.254)
				(xy -0.5334 -0.2794) (xy 0.5334 -0.2794) (xy 0.5334 -0.254) (xy 0.635 -0.254) (xy 0.635 0.254) (xy 0.5334 0.254)
				(xy 0.5334 0.2794)
			)
			(stroke
				(width 0)
				(type default)
			)
			(fill no)
			(layer "F.CrtYd")
		)
		(pad "1" smd rect
			(at 0.40005 0 180)
			(size 0.4572 0.508)
			(layers "F.Cu" "F.Mask" "F.Paste")
			(net "LED_SATA_NODE1_R")
		)
		(pad "2" smd rect
			(at -0.40005 0 180)
			(size 0.4572 0.508)
			(layers "F.Cu" "F.Mask" "F.Paste")
			(net "P3V3_NODE1")
		)
	)
	(footprint ""
		(layer "F.Cu")
		(at 53.561996 -162.046158 180)
		(property "Reference" "C519"
			(at 0.575564 5.663692 0)
			(unlocked yes)
			(layer "F.SilkS")
			(effects
				(font
					(size 0.7874 0.5842)
					(thickness 0.1524)
				)
				(justify left)
			)
		)
		(property "Value" ""
			(at 0 0 180)
			(layer "F.Fab")
			(effects
				(font
					(size 1.27 1.27)
				)
			)
		)
		(duplicate_pad_numbers_are_jumpers no)
		(fp_line
			(start 0.7874 0.4064)
			(end -0.7874 0.4064)
			(stroke
				(width 0.1524)
				(type default)
			)
			(layer "F.SilkS")
		)
		(fp_line
			(start 0.7874 -0.4064)
			(end 0.7874 0.4064)
			(stroke
				(width 0.1524)
				(type default)
			)
			(layer "F.SilkS")
		)
		(fp_line
			(start 0 0.381)
			(end 0 -0.381)
			(stroke
				(width 0.1524)
				(type default)
			)
			(layer "F.SilkS")
		)
		(fp_line
			(start -0.7874 0.4064)
			(end -0.7874 -0.4064)
			(stroke
				(width 0.1524)
				(type default)
			)
			(layer "F.SilkS")
		)
		(fp_line
			(start -0.7874 -0.4064)
			(end 0.7874 -0.4064)
			(stroke
				(width 0.1524)
				(type default)
			)
			(layer "F.SilkS")
		)
		(fp_poly
			(pts
				(xy -0.5334 0.254) (xy -0.635 0.254) (xy -0.635 0.2286) (xy -0.635 -0.254) (xy -0.5334 -0.254) (xy -0.5334 -0.2794)
				(xy 0.5334 -0.2794) (xy 0.5334 -0.254) (xy 0.635 -0.254) (xy 0.635 0.254) (xy 0.5334 0.254) (xy 0.5334 0.2794)
				(xy -0.508 0.2794) (xy -0.5334 0.2794)
			)
			(stroke
				(width 0)
				(type default)
			)
			(fill no)
			(layer "F.CrtYd")
		)
		(pad "1" smd rect
			(at 0.40005 0 180)
			(size 0.4572 0.508)
			(layers "F.Cu" "F.Mask" "F.Paste")
			(net "LAN1_LED_LINK_1000_N")
		)
		(pad "2" smd rect
			(at -0.40005 0 180)
			(size 0.4572 0.508)
			(layers "F.Cu" "F.Mask" "F.Paste")
			(net "GND")
		)
	)
	(footprint ""
		(layer "F.Cu")
		(at 131.99745 -60.930282 90)
		(property "Reference" "R519"
			(at -1.062482 -2.10058 90)
			(unlocked yes)
			(layer "F.SilkS")
			(effects
				(font
					(size 0.7874 0.5842)
					(thickness 0.1524)
				)
				(justify left)
			)
		)
		(property "Value" ""
			(at 0 0 90)
			(layer "F.Fab")
			(effects
				(font
					(size 1.27 1.27)
				)
			)
		)
		(duplicate_pad_numbers_are_jumpers no)
		(fp_line
			(start 0.7874 -0.4064)
			(end 0.7874 0.4064)
			(stroke
				(width 0.1524)
				(type default)
			)
			(layer "F.SilkS")
		)
		(fp_line
			(start -0.7874 -0.4064)
			(end 0.7874 -0.4064)
			(stroke
				(width 0.1524)
				(type default)
			)
			(layer "F.SilkS")
		)
		(fp_line
			(start 0.7874 0.4064)
			(end -0.7874 0.4064)
			(stroke
				(width 0.1524)
				(type default)
			)
			(layer "F.SilkS")
		)
		(fp_line
			(start -0.7874 0.4064)
			(end -0.7874 -0.4064)
			(stroke
				(width 0.1524)
				(type default)
			)
			(layer "F.SilkS")
		)
		(fp_poly
			(pts
				(xy -0.508 0.2794) (xy -0.508 0.2286) (xy -0.635 0.2286) (xy -0.635 -0.254) (xy -0.5334 -0.254)
				(xy -0.5334 -0.2794) (xy 0.5334 -0.2794) (xy 0.5334 -0.254) (xy 0.635 -0.254) (xy 0.635 0.254) (xy 0.5334 0.254)
				(xy 0.5334 0.2794)
			)
			(stroke
				(width 0)
				(type default)
			)
			(fill no)
			(layer "F.CrtYd")
		)
		(pad "1" smd rect
			(at 0.40005 0 90)
			(size 0.4572 0.508)
			(layers "F.Cu" "F.Mask" "F.Paste")
			(net "SATA_SPI_DI_NODE1_R")
		)
		(pad "2" smd rect
			(at -0.40005 0 90)
			(size 0.4572 0.508)
			(layers "F.Cu" "F.Mask" "F.Paste")
			(net "SATA_SPI_DI_NODE1")
		)
	)
	(footprint ""
		(layer "F.Cu")
		(at 89.562178 -107.83824)
		(property "Reference" "R177"
			(at -1.189482 -1.14427 0)
			(unlocked yes)
			(layer "F.SilkS")
			(effects
				(font
					(size 0.7874 0.5842)
					(thickness 0.1524)
				)
				(justify left)
			)
		)
		(property "Value" ""
			(at 0 0 0)
			(layer "F.Fab")
			(effects
				(font
					(size 1.27 1.27)
				)
			)
		)
		(duplicate_pad_numbers_are_jumpers no)
		(fp_line
			(start -0.7874 -0.4064)
			(end 0.7874 -0.4064)
			(stroke
				(width 0.1524)
				(type default)
			)
			(layer "F.SilkS")
		)
		(fp_line
			(start -0.7874 0.4064)
			(end -0.7874 -0.4064)
			(stroke
				(width 0.1524)
				(type default)
			)
			(layer "F.SilkS")
		)
		(fp_line
			(start 0.7874 -0.4064)
			(end 0.7874 0.4064)
			(stroke
				(width 0.1524)
				(type default)
			)
			(layer "F.SilkS")
		)
		(fp_line
			(start 0.7874 0.4064)
			(end -0.7874 0.4064)
			(stroke
				(width 0.1524)
				(type default)
			)
			(layer "F.SilkS")
		)
		(fp_poly
			(pts
				(xy -0.508 0.2794) (xy -0.508 0.2286) (xy -0.635 0.2286) (xy -0.635 -0.254) (xy -0.5334 -0.254)
				(xy -0.5334 -0.2794) (xy 0.5334 -0.2794) (xy 0.5334 -0.254) (xy 0.635 -0.254) (xy 0.635 0.254) (xy 0.5334 0.254)
				(xy 0.5334 0.2794)
			)
			(stroke
				(width 0)
				(type default)
			)
			(fill no)
			(layer "F.CrtYd")
		)
		(pad "1" smd rect
			(at 0.40005 0)
			(size 0.4572 0.508)
			(layers "F.Cu" "F.Mask" "F.Paste")
			(net "P3V3_NODE1")
		)
		(pad "2" smd rect
			(at -0.40005 0)
			(size 0.4572 0.508)
			(layers "F.Cu" "F.Mask" "F.Paste")
			(net "SPI_CPU_NODE1_HOLD_L")
		)
	)
	(footprint ""
		(layer "F.Cu")
		(at 53.561996 -161.030158 180)
		(property "Reference" "C518"
			(at 0.575564 5.564632 0)
			(unlocked yes)
			(layer "F.SilkS")
			(effects
				(font
					(size 0.7874 0.5842)
					(thickness 0.1524)
				)
				(justify left)
			)
		)
		(property "Value" ""
			(at 0 0 180)
			(layer "F.Fab")
			(effects
				(font
					(size 1.27 1.27)
				)
			)
		)
		(duplicate_pad_numbers_are_jumpers no)
		(fp_line
			(start 0.7874 0.4064)
			(end -0.7874 0.4064)
			(stroke
				(width 0.1524)
				(type default)
			)
			(layer "F.SilkS")
		)
		(fp_line
			(start 0.7874 -0.4064)
			(end 0.7874 0.4064)
			(stroke
				(width 0.1524)
				(type default)
			)
			(layer "F.SilkS")
		)
		(fp_line
			(start 0 0.381)
			(end 0 -0.381)
			(stroke
				(width 0.1524)
				(type default)
			)
			(layer "F.SilkS")
		)
		(fp_line
			(start -0.7874 0.4064)
			(end -0.7874 -0.4064)
			(stroke
				(width 0.1524)
				(type default)
			)
			(layer "F.SilkS")
		)
		(fp_line
			(start -0.7874 -0.4064)
			(end 0.7874 -0.4064)
			(stroke
				(width 0.1524)
				(type default)
			)
			(layer "F.SilkS")
		)
		(fp_poly
			(pts
				(xy -0.5334 0.254) (xy -0.635 0.254) (xy -0.635 0.2286) (xy -0.635 -0.254) (xy -0.5334 -0.254) (xy -0.5334 -0.2794)
				(xy 0.5334 -0.2794) (xy 0.5334 -0.254) (xy 0.635 -0.254) (xy 0.635 0.254) (xy 0.5334 0.254) (xy 0.5334 0.2794)
				(xy -0.508 0.2794) (xy -0.5334 0.2794)
			)
			(stroke
				(width 0)
				(type default)
			)
			(fill no)
			(layer "F.CrtYd")
		)
		(pad "1" smd rect
			(at 0.40005 0 180)
			(size 0.4572 0.508)
			(layers "F.Cu" "F.Mask" "F.Paste")
			(net "LAN1_LED_LINK_100_N")
		)
		(pad "2" smd rect
			(at -0.40005 0 180)
			(size 0.4572 0.508)
			(layers "F.Cu" "F.Mask" "F.Paste")
			(net "GND")
		)
	)
	(footprint ""
		(layer "F.Cu")
		(at 130.08356 -188.126624 90)
		(property "Reference" "C758"
			(at 4.949444 -0.710438 90)
			(unlocked yes)
			(layer "F.SilkS")
			(effects
				(font
					(size 0.7874 0.5842)
					(thickness 0.1524)
				)
				(justify left)
			)
		)
		(property "Value" ""
			(at 0 0 90)
			(layer "F.Fab")
			(effects
				(font
					(size 1.27 1.27)
				)
			)
		)
		(duplicate_pad_numbers_are_jumpers no)
		(fp_line
			(start 0.7874 -0.4064)
			(end 0.7874 0.4064)
			(stroke
				(width 0.1524)
				(type default)
			)
			(layer "F.SilkS")
		)
		(fp_line
			(start -0.7874 -0.4064)
			(end 0.7874 -0.4064)
			(stroke
				(width 0.1524)
				(type default)
			)
			(layer "F.SilkS")
		)
		(fp_line
			(start 0 0.381)
			(end 0 -0.381)
			(stroke
				(width 0.1524)
				(type default)
			)
			(layer "F.SilkS")
		)
		(fp_line
			(start 0.7874 0.4064)
			(end -0.7874 0.4064)
			(stroke
				(width 0.1524)
				(type default)
			)
			(layer "F.SilkS")
		)
		(fp_line
			(start -0.7874 0.4064)
			(end -0.7874 -0.4064)
			(stroke
				(width 0.1524)
				(type default)
			)
			(layer "F.SilkS")
		)
		(fp_poly
			(pts
				(xy -0.5334 0.254) (xy -0.635 0.254) (xy -0.635 0.2286) (xy -0.635 -0.254) (xy -0.5334 -0.254) (xy -0.5334 -0.2794)
				(xy 0.5334 -0.2794) (xy 0.5334 -0.254) (xy 0.635 -0.254) (xy 0.635 0.254) (xy 0.5334 0.254) (xy 0.5334 0.2794)
				(xy -0.508 0.2794) (xy -0.5334 0.2794)
			)
			(stroke
				(width 0)
				(type default)
			)
			(fill no)
			(layer "F.CrtYd")
		)
		(pad "1" smd rect
			(at 0.40005 0 90)
			(size 0.4572 0.508)
			(layers "F.Cu" "F.Mask" "F.Paste")
			(net "UART_T10_NODE3_TXD_R")
		)
		(pad "2" smd rect
			(at -0.40005 0 90)
			(size 0.4572 0.508)
			(layers "F.Cu" "F.Mask" "F.Paste")
			(net "GND")
		)
	)
	(footprint ""
		(layer "F.Cu")
		(at 15.425166 -52.298854 90)
		(property "Reference" "C506"
			(at -4.414266 14.419072 90)
			(unlocked yes)
			(layer "F.SilkS")
			(effects
				(font
					(size 0.7874 0.5842)
					(thickness 0.1524)
				)
				(justify left)
			)
		)
		(property "Value" ""
			(at 0 0 90)
			(layer "F.Fab")
			(effects
				(font
					(size 1.27 1.27)
				)
			)
		)
		(duplicate_pad_numbers_are_jumpers no)
		(fp_line
			(start 0.7874 -0.4064)
			(end 0.7874 0.4064)
			(stroke
				(width 0.1524)
				(type default)
			)
			(layer "F.SilkS")
		)
		(fp_line
			(start -0.7874 -0.4064)
			(end 0.7874 -0.4064)
			(stroke
				(width 0.1524)
				(type default)
			)
			(layer "F.SilkS")
		)
		(fp_line
			(start 0 0.381)
			(end 0 -0.381)
			(stroke
				(width 0.1524)
				(type default)
			)
			(layer "F.SilkS")
		)
		(fp_line
			(start 0.7874 0.4064)
			(end -0.7874 0.4064)
			(stroke
				(width 0.1524)
				(type default)
			)
			(layer "F.SilkS")
		)
		(fp_line
			(start -0.7874 0.4064)
			(end -0.7874 -0.4064)
			(stroke
				(width 0.1524)
				(type default)
			)
			(layer "F.SilkS")
		)
		(fp_poly
			(pts
				(xy -0.5334 0.254) (xy -0.635 0.254) (xy -0.635 0.2286) (xy -0.635 -0.254) (xy -0.5334 -0.254) (xy -0.5334 -0.2794)
				(xy 0.5334 -0.2794) (xy 0.5334 -0.254) (xy 0.635 -0.254) (xy 0.635 0.254) (xy 0.5334 0.254) (xy 0.5334 0.2794)
				(xy -0.508 0.2794) (xy -0.5334 0.2794)
			)
			(stroke
				(width 0)
				(type default)
			)
			(fill no)
			(layer "F.CrtYd")
		)
		(pad "1" smd rect
			(at 0.40005 0 90)
			(size 0.4572 0.508)
			(layers "F.Cu" "F.Mask" "F.Paste")
			(net "CRT_HSYNC")
		)
		(pad "2" smd rect
			(at -0.40005 0 90)
			(size 0.4572 0.508)
			(layers "F.Cu" "F.Mask" "F.Paste")
			(net "GND")
		)
	)
	(footprint ""
		(layer "F.Cu")
		(at 108.388404 -153.54808)
		(property "Reference" "R657"
			(at -1.084326 5.395976 0)
			(unlocked yes)
			(layer "F.SilkS")
			(effects
				(font
					(size 0.635 0.4064)
					(thickness 0.1524)
				)
				(justify left)
			)
		)
		(property "Value" ""
			(at 0 0 0)
			(layer "F.Fab")
			(effects
				(font
					(size 1.27 1.27)
				)
			)
		)
		(duplicate_pad_numbers_are_jumpers no)
		(fp_line
			(start -0.7874 -0.4064)
			(end 0.7874 -0.4064)
			(stroke
				(width 0.1524)
				(type default)
			)
			(layer "F.SilkS")
		)
		(fp_line
			(start -0.7874 0.4064)
			(end -0.7874 -0.4064)
			(stroke
				(width 0.1524)
				(type default)
			)
			(layer "F.SilkS")
		)
		(fp_line
			(start 0.7874 -0.4064)
			(end 0.7874 0.4064)
			(stroke
				(width 0.1524)
				(type default)
			)
			(layer "F.SilkS")
		)
		(fp_line
			(start 0.7874 0.4064)
			(end -0.7874 0.4064)
			(stroke
				(width 0.1524)
				(type default)
			)
			(layer "F.SilkS")
		)
		(fp_poly
			(pts
				(xy -0.508 0.2794) (xy -0.508 0.2286) (xy -0.635 0.2286) (xy -0.635 -0.254) (xy -0.5334 -0.254)
				(xy -0.5334 -0.2794) (xy 0.5334 -0.2794) (xy 0.5334 -0.254) (xy 0.635 -0.254) (xy 0.635 0.254) (xy 0.5334 0.254)
				(xy 0.5334 0.2794)
			)
			(stroke
				(width 0)
				(type default)
			)
			(fill no)
			(layer "F.CrtYd")
		)
		(pad "1" smd rect
			(at 0.40005 0)
			(size 0.4572 0.508)
			(layers "F.Cu" "F.Mask" "F.Paste")
			(net "N52411212")
		)
		(pad "2" smd rect
			(at -0.40005 0)
			(size 0.4572 0.508)
			(layers "F.Cu" "F.Mask" "F.Paste")
			(net "P12V_AUX")
		)
	)
)
